# T6G (Grand Teton) — schematic netlist excerpt (pin names and nets, part order shuffled) for the footprints in the layout excerpt that follows; sources: Cadence DE-HDL packaged netlist, KiCad conversion of 04192023_DAF0TMB3IC0_F0TG_MB_C_brd_V02_OCP.brd

R1217  Q_RES  1K 1% CHIP  pkg 0201LF  page 186 : A = GND ; B = RT_ROM_MUX8_OE_N
C152  Q_CAP  0.1UF 25V 10% X7R  pkg 0402  page 102 : A = P3V3_AUX ; B = GND
C444  Q_CAP  0.1UF 10V 10% X7S  pkg C0201  page 356 : A = P1V8_CPU1_RT3_1A_1D ; B = GND
C6563  Q_CAP_DIFFBUS  DIFF BUS_0.22UF 6.3V 20% X6S  pkg C0201  page 286 : \1\ = P5E_CPU0_P1_TX_BUF_C_DP<15> ; \2\ = P5E_CPU0_P1_TX_BUF_DP<15>
R973  Q_RES  200 1% CHIP  pkg 0201LF  page 276 : A = RT_CPU0_P0_SCAN_MODE ; B = GND

(kicad_pcb
	(version 20260206)
	(generator "pcbnew")
	(generator_version "10.0")
	(general
		(thickness 1.6)
		(legacy_teardrops no)
	)
	(paper "A4")
	(title_block
		(title "04192023_DAF0TMB3IC0_F0TG_MB_C_brd_V02_OCP.brd")
		(comment 1 "Grand Teton / footprints 5062-5066 of 8354")
	)
	(layers
		(0 "F.Cu" signal "TOP")
		(4 "In1.Cu" signal "GND")
		(6 "In2.Cu" signal "IN1")
		(8 "In3.Cu" signal "GND1")
		(10 "In4.Cu" signal "IN2")
		(12 "In5.Cu" signal "GND2")
		(14 "In6.Cu" signal "IN3")
		(16 "In7.Cu" signal "GND3")
		(18 "In8.Cu" signal "VCC")
		(20 "In9.Cu" signal "VCC1")
		(22 "In10.Cu" signal "GND4")
		(24 "In11.Cu" signal "IN4")
		(26 "In12.Cu" signal "GND5")
		(28 "In13.Cu" signal "IN5")
		(30 "In14.Cu" signal "GND6")
		(32 "In15.Cu" signal "IN6")
		(34 "In16.Cu" signal "GND7")
		(2 "B.Cu" signal "BOTTOM")
		(9 "F.Adhes" user "F.Adhesive")
		(11 "B.Adhes" user "B.Adhesive")
		(13 "F.Paste" user "Package Geometry/Pastemask Top")
		(15 "B.Paste" user "Package Geometry/Pastemask Bottom")
		(5 "F.SilkS" user "Ref Des/Silkscreen Top")
		(7 "B.SilkS" user "Ref Des/Silkscreen Bottom")
		(1 "F.Mask" user "Board Geometry/Soldermask Top")
		(3 "B.Mask" user "Board Geometry/Soldermask Bottom")
		(17 "Dwgs.User" user "User.Drawings")
		(19 "Cmts.User" user "User.Comments")
		(21 "Eco1.User" user "User.Eco1")
		(23 "Eco2.User" user "User.Eco2")
		(25 "Edge.Cuts" user "Board Geometry/Outline")
		(27 "Margin" user)
		(31 "F.CrtYd" user "Package Geometry/Place Bound Top")
		(29 "B.CrtYd" user "Package Geometry/Place Bound Bottom")
		(35 "F.Fab" user "Ref Des/Assembly Top")
		(33 "B.Fab" user "Ref Des/Assembly Bottom")
	)
	(footprint ""
		(layer "B.Cu")
		(at 352.163126 -416.899344 90)
		(property "Reference" "C6563"
			(at 0 0 90)
			(layer "B.SilkS")
			(hide yes)
			(effects
				(font
					(size 1.27 1.27)
				)
				(justify mirror)
			)
		)
		(property "Value" ""
			(at 0 0 90)
			(layer "B.Fab")
			(effects
				(font
					(size 1.27 1.27)
				)
				(justify mirror)
			)
		)
		(duplicate_pad_numbers_are_jumpers no)
		(fp_line
			(start 0.299974 -0.150114)
			(end -0.299974 -0.150114)
			(stroke
				(width 0.1)
				(type default)
			)
			(layer "B.Fab")
		)
		(fp_line
			(start -0.299974 -0.150114)
			(end -0.299974 0.150114)
			(stroke
				(width 0.1)
				(type default)
			)
			(layer "B.Fab")
		)
		(fp_line
			(start 0.299974 0.150114)
			(end 0.299974 -0.150114)
			(stroke
				(width 0.1)
				(type default)
			)
			(layer "B.Fab")
		)
		(fp_line
			(start -0.299974 0.150114)
			(end 0.299974 0.150114)
			(stroke
				(width 0.1)
				(type default)
			)
			(layer "B.Fab")
		)
		(pad "1" smd rect
			(at 0.2667 0 270)
			(size 0.3048 0.381)
			(layers "B.Cu" "B.Mask" "B.Paste")
			(net "P5E_CPU0_P1_TX_BUF_C_DP<15>")
		)
		(pad "2" smd rect
			(at -0.2667 0 270)
			(size 0.3048 0.381)
			(layers "B.Cu" "B.Mask" "B.Paste")
			(net "P5E_CPU0_P1_TX_BUF_DP<15>")
		)
	)
	(footprint ""
		(layer "B.Cu")
		(at 28.46324 -193.996564)
		(property "Reference" "C152"
			(at 0 0 0)
			(layer "B.SilkS")
			(hide yes)
			(effects
				(font
					(size 1.27 1.27)
				)
				(justify mirror)
			)
		)
		(property "Value" ""
			(at 0 0 0)
			(layer "B.Fab")
			(effects
				(font
					(size 1.27 1.27)
				)
				(justify mirror)
			)
		)
		(duplicate_pad_numbers_are_jumpers no)
		(fp_line
			(start -0.7874 -0.4064)
			(end -0.7874 0.4064)
			(stroke
				(width 0.1524)
				(type default)
			)
			(layer "B.SilkS")
		)
		(fp_line
			(start -0.7874 0.4064)
			(end 0.7874 0.4064)
			(stroke
				(width 0.1524)
				(type default)
			)
			(layer "B.SilkS")
		)
		(fp_line
			(start 0.7874 -0.4064)
			(end -0.7874 -0.4064)
			(stroke
				(width 0.1524)
				(type default)
			)
			(layer "B.SilkS")
		)
		(fp_line
			(start 0.7874 0.4064)
			(end 0.7874 -0.4064)
			(stroke
				(width 0.1524)
				(type default)
			)
			(layer "B.SilkS")
		)
		(fp_line
			(start -0.67945 -0.3048)
			(end -0.67945 0.3048)
			(stroke
				(width 0.1)
				(type default)
			)
			(layer "B.Fab")
		)
		(fp_line
			(start -0.67945 0.3048)
			(end -0.120396 0.3048)
			(stroke
				(width 0.1)
				(type default)
			)
			(layer "B.Fab")
		)
		(fp_line
			(start -0.12065 -0.3048)
			(end -0.67945 -0.3048)
			(stroke
				(width 0.1)
				(type default)
			)
			(layer "B.Fab")
		)
		(fp_line
			(start -0.12065 -0.2794)
			(end -0.12065 -0.3048)
			(stroke
				(width 0.1)
				(type default)
			)
			(layer "B.Fab")
		)
		(fp_line
			(start -0.120396 0.2794)
			(end 0.12065 0.2794)
			(stroke
				(width 0.1)
				(type default)
			)
			(layer "B.Fab")
		)
		(fp_line
			(start -0.120396 0.3048)
			(end -0.120396 0.2794)
			(stroke
				(width 0.1)
				(type default)
			)
			(layer "B.Fab")
		)
		(fp_line
			(start 0.12065 -0.305054)
			(end 0.12065 -0.2794)
			(stroke
				(width 0.1)
				(type default)
			)
			(layer "B.Fab")
		)
		(fp_line
			(start 0.12065 -0.2794)
			(end -0.12065 -0.2794)
			(stroke
				(width 0.1)
				(type default)
			)
			(layer "B.Fab")
		)
		(fp_line
			(start 0.12065 0.2794)
			(end 0.12065 0.3048)
			(stroke
				(width 0.1)
				(type default)
			)
			(layer "B.Fab")
		)
		(fp_line
			(start 0.12065 0.3048)
			(end 0.67945 0.3048)
			(stroke
				(width 0.1)
				(type default)
			)
			(layer "B.Fab")
		)
		(fp_line
			(start 0.67945 -0.305054)
			(end 0.12065 -0.305054)
			(stroke
				(width 0.1)
				(type default)
			)
			(layer "B.Fab")
		)
		(fp_line
			(start 0.67945 0.3048)
			(end 0.67945 -0.305054)
			(stroke
				(width 0.1)
				(type default)
			)
			(layer "B.Fab")
		)
		(pad "1" smd circle
			(at 0.40005 0 180)
			(size 0 0)
			(layers "B.Cu" "B.Mask" "B.Paste")
			(net "P3V3_AUX")
		)
		(pad "2" smd circle
			(at -0.40005 0 180)
			(size 0 0)
			(layers "B.Cu" "B.Mask" "B.Paste")
			(net "GND")
		)
	)
	(footprint ""
		(layer "B.Cu")
		(at 299.265594 -391.88136 180)
		(property "Reference" "R973"
			(at 0 0 0)
			(layer "B.SilkS")
			(hide yes)
			(effects
				(font
					(size 1.27 1.27)
				)
				(justify mirror)
			)
		)
		(property "Value" ""
			(at 0 0 0)
			(layer "B.Fab")
			(effects
				(font
					(size 1.27 1.27)
				)
				(justify mirror)
			)
		)
		(duplicate_pad_numbers_are_jumpers no)
		(fp_line
			(start 0.32512 0.175006)
			(end 0.32512 -0.175006)
			(stroke
				(width 0.1)
				(type default)
			)
			(layer "B.Fab")
		)
		(fp_line
			(start 0.32512 -0.175006)
			(end -0.32512 -0.175006)
			(stroke
				(width 0.1)
				(type default)
			)
			(layer "B.Fab")
		)
		(fp_line
			(start -0.32512 0.175006)
			(end 0.32512 0.175006)
			(stroke
				(width 0.1)
				(type default)
			)
			(layer "B.Fab")
		)
		(fp_line
			(start -0.32512 -0.175006)
			(end -0.32512 0.175006)
			(stroke
				(width 0.1)
				(type default)
			)
			(layer "B.Fab")
		)
		(pad "1" smd rect
			(at 0.2667 0)
			(size 0.3048 0.381)
			(layers "B.Cu" "B.Mask" "B.Paste")
			(net "RT_CPU0_P0_SCAN_MODE")
		)
		(pad "2" smd rect
			(at -0.2667 0 180)
			(size 0.3048 0.381)
			(layers "B.Cu" "B.Mask" "B.Paste")
			(net "GND")
		)
	)
	(footprint ""
		(layer "B.Cu")
		(at 125.418342 -388.011162 -90)
		(property "Reference" "C444"
			(at 0 0 90)
			(layer "B.SilkS")
			(hide yes)
			(effects
				(font
					(size 1.27 1.27)
				)
				(justify mirror)
			)
		)
		(property "Value" ""
			(at 0 0 90)
			(layer "B.Fab")
			(effects
				(font
					(size 1.27 1.27)
				)
				(justify mirror)
			)
		)
		(duplicate_pad_numbers_are_jumpers no)
		(fp_line
			(start -0.299974 0.150114)
			(end 0.299974 0.150114)
			(stroke
				(width 0.1)
				(type default)
			)
			(layer "B.Fab")
		)
		(fp_line
			(start 0.299974 0.150114)
			(end 0.299974 -0.150114)
			(stroke
				(width 0.1)
				(type default)
			)
			(layer "B.Fab")
		)
		(fp_line
			(start -0.299974 -0.150114)
			(end -0.299974 0.150114)
			(stroke
				(width 0.1)
				(type default)
			)
			(layer "B.Fab")
		)
		(fp_line
			(start 0.299974 -0.150114)
			(end -0.299974 -0.150114)
			(stroke
				(width 0.1)
				(type default)
			)
			(layer "B.Fab")
		)
		(pad "1" smd rect
			(at 0.2667 0 90)
			(size 0.3048 0.381)
			(layers "B.Cu" "B.Mask" "B.Paste")
			(net "P1V8_CPU1_RT3_1A_1D")
		)
		(pad "2" smd rect
			(at -0.2667 0 90)
			(size 0.3048 0.381)
			(layers "B.Cu" "B.Mask" "B.Paste")
			(net "GND")
		)
	)
	(footprint ""
		(layer "B.Cu")
		(at 419.089586 -425.82338 180)
		(property "Reference" "R1217"
			(at 0 0 0)
			(layer "B.SilkS")
			(hide yes)
			(effects
				(font
					(size 1.27 1.27)
				)
				(justify mirror)
			)
		)
		(property "Value" ""
			(at 0 0 0)
			(layer "B.Fab")
			(effects
				(font
					(size 1.27 1.27)
				)
				(justify mirror)
			)
		)
		(duplicate_pad_numbers_are_jumpers no)
		(fp_line
			(start 0.32512 0.175006)
			(end 0.32512 -0.175006)
			(stroke
				(width 0.1)
				(type default)
			)
			(layer "B.Fab")
		)
		(fp_line
			(start 0.32512 -0.175006)
			(end -0.32512 -0.175006)
			(stroke
				(width 0.1)
				(type default)
			)
			(layer "B.Fab")
		)
		(fp_line
			(start -0.32512 0.175006)
			(end 0.32512 0.175006)
			(stroke
				(width 0.1)
				(type default)
			)
			(layer "B.Fab")
		)
		(fp_line
			(start -0.32512 -0.175006)
			(end -0.32512 0.175006)
			(stroke
				(width 0.1)
				(type default)
			)
			(layer "B.Fab")
		)
		(pad "1" smd rect
			(at 0.2667 0)
			(size 0.3048 0.381)
			(layers "B.Cu" "B.Mask" "B.Paste")
			(net "GND")
		)
		(pad "2" smd rect
			(at -0.2667 0 180)
			(size 0.3048 0.381)
			(layers "B.Cu" "B.Mask" "B.Paste")
			(net "RT_ROM_MUX8_OE_N")
		)
	)
)
